(kicad_pcb
	(version 20260206)
	(generator "pcbnew")
	(generator_version "10.0")
	(general
		(thickness 1.6)
		(legacy_teardrops no)
	)
	(paper "A4")
	(title_block
		(title "03242023_DA0F0TMBIJ0_F0T_Motherboard_J_brd_V01_OCP.brd")
		(comment 1 "Grand Teton / footprints 3498-3504 of 6105")
	)
	(layers
		(0 "F.Cu" signal "TOP")
		(4 "In1.Cu" signal "GND")
		(6 "In2.Cu" signal "IN1")
		(8 "In3.Cu" signal "GND1")
		(10 "In4.Cu" signal "IN2")
		(12 "In5.Cu" signal "GND2")
		(14 "In6.Cu" signal "IN3")
		(16 "In7.Cu" signal "GND3")
		(18 "In8.Cu" signal "VCC")
		(20 "In9.Cu" signal "VCC1")
		(22 "In10.Cu" signal "GND4")
		(24 "In11.Cu" signal "IN4")
		(26 "In12.Cu" signal "GND5")
		(28 "In13.Cu" signal "IN5")
		(30 "In14.Cu" signal "GND6")
		(32 "In15.Cu" signal "IN6")
		(34 "In16.Cu" signal "GND7")
		(2 "B.Cu" signal "BOTTOM")
		(9 "F.Adhes" user "F.Adhesive")
		(11 "B.Adhes" user "B.Adhesive")
		(13 "F.Paste" user "Package Geometry/Pastemask Top")
		(15 "B.Paste" user "Package Geometry/Pastemask Bottom")
		(5 "F.SilkS" user "Ref Des/Silkscreen Top")
		(7 "B.SilkS" user "Ref Des/Silkscreen Bottom")
		(1 "F.Mask" user "Board Geometry/Soldermask Top")
		(3 "B.Mask" user "Board Geometry/Soldermask Bottom")
		(17 "Dwgs.User" user "User.Drawings")
		(19 "Cmts.User" user "User.Comments")
		(21 "Eco1.User" user "User.Eco1")
		(23 "Eco2.User" user "User.Eco2")
		(25 "Edge.Cuts" user "Board Geometry/Outline")
		(27 "Margin" user)
		(31 "F.CrtYd" user "Package Geometry/Place Bound Top")
		(29 "B.CrtYd" user "Package Geometry/Place Bound Bottom")
		(35 "F.Fab" user "Ref Des/Assembly Top")
		(33 "B.Fab" user "Ref Des/Assembly Bottom")
	)
	(footprint ""
		(layer "F.Cu")
		(at 504.058428 -303.58588 90)
		(property "Reference" "X3"
			(at -2.637536 3.163062 90)
			(unlocked yes)
			(layer "F.SilkS")
			(effects
				(font
					(size 0.7874 0.5842)
					(thickness 0.1524)
				)
				(justify left)
			)
		)
		(property "Value" ""
			(at 0 0 90)
			(layer "F.Fab")
			(effects
				(font
					(size 1.27 1.27)
				)
			)
		)
		(property "Device Type" "TP_TDR_4P_FTS_MPKT4_H025P0200_I"
			(at 1.30175 1.27 180)
			(unlocked yes)
			(layer "F.Fab")
			(hide yes)
			(effects
				(font
					(size 0.635 0.4064)
					(thickness 0.1524)
				)
			)
		)
		(property "User Part Number" "TP15"
			(at 1.30175 1.27 180)
			(unlocked yes)
			(layer "Cmts.User")
			(hide yes)
			(effects
				(font
					(size 0.635 0.4064)
					(thickness 0.1524)
				)
			)
		)
		(duplicate_pad_numbers_are_jumpers no)
		(fp_line
			(start 2.54 -1.27)
			(end 0 -1.27)
			(stroke
				(width 0.1524)
				(type default)
			)
			(layer "F.SilkS")
		)
		(fp_line
			(start 0 -1.27)
			(end 0 -0.635)
			(stroke
				(width 0.1524)
				(type default)
			)
			(layer "F.SilkS")
		)
		(fp_line
			(start 2.54 -1.1303)
			(end 2.54 -1.27)
			(stroke
				(width 0.1524)
				(type default)
			)
			(layer "F.SilkS")
		)
		(fp_line
			(start 0 0.635)
			(end 0 1.905)
			(stroke
				(width 0.1524)
				(type default)
			)
			(layer "F.SilkS")
		)
		(fp_line
			(start 2.54 1.4097)
			(end 2.54 1.1303)
			(stroke
				(width 0.1524)
				(type default)
			)
			(layer "F.SilkS")
		)
		(fp_line
			(start 0 3.175)
			(end 0 3.81)
			(stroke
				(width 0.1524)
				(type default)
			)
			(layer "F.SilkS")
		)
		(fp_line
			(start 2.54 3.81)
			(end 2.54 3.6703)
			(stroke
				(width 0.1524)
				(type default)
			)
			(layer "F.SilkS")
		)
		(fp_line
			(start 0 3.81)
			(end 2.54 3.81)
			(stroke
				(width 0.1524)
				(type default)
			)
			(layer "F.SilkS")
		)
		(fp_poly
			(pts
				(xy -0.761746 0) (xy -2.285746 0.762) (xy -2.285746 -0.762)
			)
			(stroke
				(width 0)
				(type default)
			)
			(fill yes)
			(layer "F.SilkS")
		)
		(fp_line
			(start 2.54 -1.27)
			(end 0 -1.27)
			(stroke
				(width 0.1)
				(type default)
			)
			(layer "F.Fab")
		)
		(fp_line
			(start 0 -1.27)
			(end 0 3.81)
			(stroke
				(width 0.1)
				(type default)
			)
			(layer "F.Fab")
		)
		(fp_line
			(start 2.54 3.81)
			(end 2.54 -1.27)
			(stroke
				(width 0.1)
				(type default)
			)
			(layer "F.Fab")
		)
		(fp_line
			(start 0 3.81)
			(end 2.54 3.81)
			(stroke
				(width 0.1)
				(type default)
			)
			(layer "F.Fab")
		)
		(fp_poly
			(pts
				(xy -0.761746 0) (xy -2.285746 -0.762) (xy -2.285746 0.762)
			)
			(stroke
				(width 0)
				(type default)
			)
			(fill yes)
			(layer "F.Fab")
		)
		(pad "1" thru_hole circle
			(at 0 0 90)
			(size 1.0033 1.0033)
			(drill 0.249936)
			(layers "*.Cu" "*.Mask")
			(remove_unused_layers no)
			(net "TDR_DIFF_85_IN2_DP")
			(clearance 0.10795)
			(thermal_gap 0.10795)
			(padstack
				(mode front_inner_back)
				(layer "Inner"
					(shape circle)
					(size 0.8001 0.8001)
					(clearance 0.1524)
				)
				(layer "B.Cu"
					(shape circle)
					(size 1.0033 1.0033)
					(clearance 0.10795)
				)
			)
		)
		(pad "2" thru_hole circle
			(at 2.54 0 90)
			(size 1.9939 1.9939)
			(drill 0.249936)
			(layers "*.Cu" "*.Mask")
			(remove_unused_layers no)
			(net "T1_GND")
			(clearance 0.10795)
			(thermal_gap 0.10795)
			(padstack
				(mode front_inner_back)
				(layer "Inner"
					(shape circle)
					(size 0.8001 0.8001)
					(clearance 0.1524)
				)
				(layer "B.Cu"
					(shape circle)
					(size 1.9939 1.9939)
					(clearance 0.10795)
				)
			)
		)
		(pad "3" thru_hole circle
			(at 2.54 2.54 90)
			(size 1.9939 1.9939)
			(drill 0.249936)
			(layers "*.Cu" "*.Mask")
			(remove_unused_layers no)
			(net "T1_GND")
			(clearance 0.10795)
			(thermal_gap 0.10795)
			(padstack
				(mode front_inner_back)
				(layer "Inner"
					(shape circle)
					(size 0.8001 0.8001)
					(clearance 0.1524)
				)
				(layer "B.Cu"
					(shape circle)
					(size 1.9939 1.9939)
					(clearance 0.10795)
				)
			)
		)
		(pad "4" thru_hole circle
			(at 0 2.54 90)
			(size 1.0033 1.0033)
			(drill 0.249936)
			(layers "*.Cu" "*.Mask")
			(remove_unused_layers no)
			(net "TDR_DIFF_85_IN2_DN")
			(clearance 0.10795)
			(thermal_gap 0.10795)
			(padstack
				(mode front_inner_back)
				(layer "Inner"
					(shape circle)
					(size 0.8001 0.8001)
					(clearance 0.1524)
				)
				(layer "B.Cu"
					(shape circle)
					(size 1.0033 1.0033)
					(clearance 0.10795)
				)
			)
		)
	)
	(footprint ""
		(layer "F.Cu")
		(at 444.598552 -25.477978)
		(property "Reference" "PC2160"
			(at 0 0 0)
			(layer "F.SilkS")
			(hide yes)
			(effects
				(font
					(size 1.27 1.27)
				)
			)
		)
		(property "Value" ""
			(at 0 0 0)
			(layer "F.Fab")
			(effects
				(font
					(size 1.27 1.27)
				)
			)
		)
		(duplicate_pad_numbers_are_jumpers no)
		(fp_line
			(start -0.7874 -0.4064)
			(end 0.7874 -0.4064)
			(stroke
				(width 0.1524)
				(type default)
			)
			(layer "F.SilkS")
		)
		(fp_line
			(start -0.7874 0.4064)
			(end -0.7874 -0.4064)
			(stroke
				(width 0.1524)
				(type default)
			)
			(layer "F.SilkS")
		)
		(fp_line
			(start 0.7874 -0.4064)
			(end 0.7874 0.4064)
			(stroke
				(width 0.1524)
				(type default)
			)
			(layer "F.SilkS")
		)
		(fp_line
			(start 0.7874 0.4064)
			(end -0.7874 0.4064)
			(stroke
				(width 0.1524)
				(type default)
			)
			(layer "F.SilkS")
		)
		(fp_line
			(start -0.67945 -0.305054)
			(end -0.12065 -0.305054)
			(stroke
				(width 0.1)
				(type default)
			)
			(layer "F.Fab")
		)
		(fp_line
			(start -0.67945 0.3048)
			(end -0.67945 -0.305054)
			(stroke
				(width 0.1)
				(type default)
			)
			(layer "F.Fab")
		)
		(fp_line
			(start -0.12065 -0.305054)
			(end -0.12065 -0.2794)
			(stroke
				(width 0.1)
				(type default)
			)
			(layer "F.Fab")
		)
		(fp_line
			(start -0.12065 -0.2794)
			(end 0.12065 -0.2794)
			(stroke
				(width 0.1)
				(type default)
			)
			(layer "F.Fab")
		)
		(fp_line
			(start -0.12065 0.2794)
			(end -0.12065 0.3048)
			(stroke
				(width 0.1)
				(type default)
			)
			(layer "F.Fab")
		)
		(fp_line
			(start -0.12065 0.3048)
			(end -0.67945 0.3048)
			(stroke
				(width 0.1)
				(type default)
			)
			(layer "F.Fab")
		)
		(fp_line
			(start 0.120396 0.2794)
			(end -0.12065 0.2794)
			(stroke
				(width 0.1)
				(type default)
			)
			(layer "F.Fab")
		)
		(fp_line
			(start 0.120396 0.3048)
			(end 0.120396 0.2794)
			(stroke
				(width 0.1)
				(type default)
			)
			(layer "F.Fab")
		)
		(fp_line
			(start 0.12065 -0.3048)
			(end 0.67945 -0.3048)
			(stroke
				(width 0.1)
				(type default)
			)
			(layer "F.Fab")
		)
		(fp_line
			(start 0.12065 -0.2794)
			(end 0.12065 -0.3048)
			(stroke
				(width 0.1)
				(type default)
			)
			(layer "F.Fab")
		)
		(fp_line
			(start 0.67945 -0.3048)
			(end 0.67945 0.3048)
			(stroke
				(width 0.1)
				(type default)
			)
			(layer "F.Fab")
		)
		(fp_line
			(start 0.67945 0.3048)
			(end 0.120396 0.3048)
			(stroke
				(width 0.1)
				(type default)
			)
			(layer "F.Fab")
		)
		(pad "1" smd circle
			(at -0.40005 0)
			(size 0 0)
			(layers "F.Cu" "F.Mask" "F.Paste")
			(net "P12V_OCP_SFF")
		)
		(pad "2" smd circle
			(at 0.40005 0)
			(size 0 0)
			(layers "F.Cu" "F.Mask" "F.Paste")
			(net "GND")
		)
	)
	(footprint ""
		(layer "F.Cu")
		(at 47.954438 -402.371052 -90)
		(property "Reference" "C710"
			(at 0 0 270)
			(layer "F.SilkS")
			(hide yes)
			(effects
				(font
					(size 1.27 1.27)
				)
			)
		)
		(property "Value" ""
			(at 0 0 270)
			(layer "F.Fab")
			(effects
				(font
					(size 1.27 1.27)
				)
			)
		)
		(duplicate_pad_numbers_are_jumpers no)
		(fp_line
			(start -0.299974 0.150114)
			(end -0.299974 -0.150114)
			(stroke
				(width 0.1)
				(type default)
			)
			(layer "F.Fab")
		)
		(fp_line
			(start 0.299974 0.150114)
			(end -0.299974 0.150114)
			(stroke
				(width 0.1)
				(type default)
			)
			(layer "F.Fab")
		)
		(fp_line
			(start -0.299974 -0.150114)
			(end 0.299974 -0.150114)
			(stroke
				(width 0.1)
				(type default)
			)
			(layer "F.Fab")
		)
		(fp_line
			(start 0.299974 -0.150114)
			(end 0.299974 0.150114)
			(stroke
				(width 0.1)
				(type default)
			)
			(layer "F.Fab")
		)
		(pad "1" smd rect
			(at -0.2667 0 270)
			(size 0.3048 0.381)
			(layers "F.Cu" "F.Mask" "F.Paste")
			(net "P5E_CPU1_PE0_TX_C_DN<15>")
		)
		(pad "2" smd rect
			(at 0.2667 0 270)
			(size 0.3048 0.381)
			(layers "F.Cu" "F.Mask" "F.Paste")
			(net "P5E_CPU1_PE0_TX_DN<15>")
		)
	)
	(footprint ""
		(layer "F.Cu")
		(at 365.46663 -251.375418 90)
		(property "Reference" "C1036"
			(at 0 0 90)
			(layer "F.SilkS")
			(hide yes)
			(effects
				(font
					(size 1.27 1.27)
				)
			)
		)
		(property "Value" ""
			(at 0 0 90)
			(layer "F.Fab")
			(effects
				(font
					(size 1.27 1.27)
				)
			)
		)
		(duplicate_pad_numbers_are_jumpers no)
		(fp_line
			(start 0.7874 -0.4064)
			(end 0.7874 0.4064)
			(stroke
				(width 0.1524)
				(type default)
			)
			(layer "F.SilkS")
		)
		(fp_line
			(start -0.7874 -0.4064)
			(end 0.7874 -0.4064)
			(stroke
				(width 0.1524)
				(type default)
			)
			(layer "F.SilkS")
		)
		(fp_line
			(start 0.7874 0.4064)
			(end -0.7874 0.4064)
			(stroke
				(width 0.1524)
				(type default)
			)
			(layer "F.SilkS")
		)
		(fp_line
			(start -0.7874 0.4064)
			(end -0.7874 -0.4064)
			(stroke
				(width 0.1524)
				(type default)
			)
			(layer "F.SilkS")
		)
		(fp_line
			(start -0.12065 -0.305054)
			(end -0.12065 -0.2794)
			(stroke
				(width 0.1)
				(type default)
			)
			(layer "F.Fab")
		)
		(fp_line
			(start -0.67945 -0.305054)
			(end -0.12065 -0.305054)
			(stroke
				(width 0.1)
				(type default)
			)
			(layer "F.Fab")
		)
		(fp_line
			(start 0.67945 -0.3048)
			(end 0.67945 0.3048)
			(stroke
				(width 0.1)
				(type default)
			)
			(layer "F.Fab")
		)
		(fp_line
			(start 0.12065 -0.3048)
			(end 0.67945 -0.3048)
			(stroke
				(width 0.1)
				(type default)
			)
			(layer "F.Fab")
		)
		(fp_line
			(start 0.12065 -0.2794)
			(end 0.12065 -0.3048)
			(stroke
				(width 0.1)
				(type default)
			)
			(layer "F.Fab")
		)
		(fp_line
			(start -0.12065 -0.2794)
			(end 0.12065 -0.2794)
			(stroke
				(width 0.1)
				(type default)
			)
			(layer "F.Fab")
		)
		(fp_line
			(start 0.120396 0.2794)
			(end -0.12065 0.2794)
			(stroke
				(width 0.1)
				(type default)
			)
			(layer "F.Fab")
		)
		(fp_line
			(start -0.12065 0.2794)
			(end -0.12065 0.3048)
			(stroke
				(width 0.1)
				(type default)
			)
			(layer "F.Fab")
		)
		(fp_line
			(start 0.67945 0.3048)
			(end 0.120396 0.3048)
			(stroke
				(width 0.1)
				(type default)
			)
			(layer "F.Fab")
		)
		(fp_line
			(start 0.120396 0.3048)
			(end 0.120396 0.2794)
			(stroke
				(width 0.1)
				(type default)
			)
			(layer "F.Fab")
		)
		(fp_line
			(start -0.12065 0.3048)
			(end -0.67945 0.3048)
			(stroke
				(width 0.1)
				(type default)
			)
			(layer "F.Fab")
		)
		(fp_line
			(start -0.67945 0.3048)
			(end -0.67945 -0.305054)
			(stroke
				(width 0.1)
				(type default)
			)
			(layer "F.Fab")
		)
		(pad "1" smd circle
			(at -0.40005 0 90)
			(size 0 0)
			(layers "F.Cu" "F.Mask" "F.Paste")
			(net "PVCCIN_CPU0")
		)
		(pad "2" smd circle
			(at 0.40005 0 90)
			(size 0 0)
			(layers "F.Cu" "F.Mask" "F.Paste")
			(net "GND")
		)
	)
	(footprint ""
		(layer "F.Cu")
		(at 61.553598 -408.517344 -90)
		(property "Reference" "C700"
			(at 0 0 270)
			(layer "F.SilkS")
			(hide yes)
			(effects
				(font
					(size 1.27 1.27)
				)
			)
		)
		(property "Value" ""
			(at 0 0 270)
			(layer "F.Fab")
			(effects
				(font
					(size 1.27 1.27)
				)
			)
		)
		(duplicate_pad_numbers_are_jumpers no)
		(fp_line
			(start -0.299974 0.150114)
			(end -0.299974 -0.150114)
			(stroke
				(width 0.1)
				(type default)
			)
			(layer "F.Fab")
		)
		(fp_line
			(start 0.299974 0.150114)
			(end -0.299974 0.150114)
			(stroke
				(width 0.1)
				(type default)
			)
			(layer "F.Fab")
		)
		(fp_line
			(start -0.299974 -0.150114)
			(end 0.299974 -0.150114)
			(stroke
				(width 0.1)
				(type default)
			)
			(layer "F.Fab")
		)
		(fp_line
			(start 0.299974 -0.150114)
			(end 0.299974 0.150114)
			(stroke
				(width 0.1)
				(type default)
			)
			(layer "F.Fab")
		)
		(pad "1" smd rect
			(at -0.2667 0 270)
			(size 0.3048 0.381)
			(layers "F.Cu" "F.Mask" "F.Paste")
			(net "P5E_CPU1_PE4_TX_C_DN<4>")
		)
		(pad "2" smd rect
			(at 0.2667 0 270)
			(size 0.3048 0.381)
			(layers "F.Cu" "F.Mask" "F.Paste")
			(net "P5E_CPU1_PE4_TX_DN<4>")
		)
	)
	(footprint ""
		(layer "F.Cu")
		(at 197.41388 -101.145848)
		(property "Reference" "R210"
			(at 0 0 0)
			(layer "F.SilkS")
			(hide yes)
			(effects
				(font
					(size 1.27 1.27)
				)
			)
		)
		(property "Value" ""
			(at 0 0 0)
			(layer "F.Fab")
			(effects
				(font
					(size 1.27 1.27)
				)
			)
		)
		(duplicate_pad_numbers_are_jumpers no)
		(fp_line
			(start -0.7874 -0.4064)
			(end 0.7874 -0.4064)
			(stroke
				(width 0.1524)
				(type default)
			)
			(layer "F.SilkS")
		)
		(fp_line
			(start -0.7874 0.4064)
			(end -0.7874 -0.4064)
			(stroke
				(width 0.1524)
				(type default)
			)
			(layer "F.SilkS")
		)
		(fp_line
			(start 0.7874 -0.4064)
			(end 0.7874 0.4064)
			(stroke
				(width 0.1524)
				(type default)
			)
			(layer "F.SilkS")
		)
		(fp_line
			(start 0.7874 0.4064)
			(end -0.7874 0.4064)
			(stroke
				(width 0.1524)
				(type default)
			)
			(layer "F.SilkS")
		)
		(fp_line
			(start -0.67945 -0.305054)
			(end -0.12065 -0.305054)
			(stroke
				(width 0.1)
				(type default)
			)
			(layer "F.Fab")
		)
		(fp_line
			(start -0.67945 0.3048)
			(end -0.67945 -0.305054)
			(stroke
				(width 0.1)
				(type default)
			)
			(layer "F.Fab")
		)
		(fp_line
			(start -0.12065 -0.305054)
			(end -0.12065 -0.2794)
			(stroke
				(width 0.1)
				(type default)
			)
			(layer "F.Fab")
		)
		(fp_line
			(start -0.12065 -0.2794)
			(end 0.12065 -0.2794)
			(stroke
				(width 0.1)
				(type default)
			)
			(layer "F.Fab")
		)
		(fp_line
			(start -0.12065 0.2794)
			(end -0.12065 0.3048)
			(stroke
				(width 0.1)
				(type default)
			)
			(layer "F.Fab")
		)
		(fp_line
			(start -0.12065 0.3048)
			(end -0.67945 0.3048)
			(stroke
				(width 0.1)
				(type default)
			)
			(layer "F.Fab")
		)
		(fp_line
			(start 0.120396 0.2794)
			(end -0.12065 0.2794)
			(stroke
				(width 0.1)
				(type default)
			)
			(layer "F.Fab")
		)
		(fp_line
			(start 0.120396 0.3048)
			(end 0.120396 0.2794)
			(stroke
				(width 0.1)
				(type default)
			)
			(layer "F.Fab")
		)
		(fp_line
			(start 0.12065 -0.3048)
			(end 0.67945 -0.3048)
			(stroke
				(width 0.1)
				(type default)
			)
			(layer "F.Fab")
		)
		(fp_line
			(start 0.12065 -0.2794)
			(end 0.12065 -0.3048)
			(stroke
				(width 0.1)
				(type default)
			)
			(layer "F.Fab")
		)
		(fp_line
			(start 0.67945 -0.3048)
			(end 0.67945 0.3048)
			(stroke
				(width 0.1)
				(type default)
			)
			(layer "F.Fab")
		)
		(fp_line
			(start 0.67945 0.3048)
			(end 0.120396 0.3048)
			(stroke
				(width 0.1)
				(type default)
			)
			(layer "F.Fab")
		)
		(pad "1" smd circle
			(at -0.40005 0)
			(size 0 0)
			(layers "F.Cu" "F.Mask" "F.Paste")
			(net "H_CPU1_MEMHOT_IN_LVC1_R_N")
		)
		(pad "2" smd circle
			(at 0.40005 0)
			(size 0 0)
			(layers "F.Cu" "F.Mask" "F.Paste")
			(net "H_CPU1_MEMHOT_IN_LVC1_R1_N")
		)
	)
	(footprint ""
		(layer "F.Cu")
		(at 165.31463 -133.77672 -90)
		(property "Reference" "R1642"
			(at 0 0 270)
			(layer "F.SilkS")
			(hide yes)
			(effects
				(font
					(size 1.27 1.27)
				)
			)
		)
		(property "Value" ""
			(at 0 0 270)
			(layer "F.Fab")
			(effects
				(font
					(size 1.27 1.27)
				)
			)
		)
		(duplicate_pad_numbers_are_jumpers no)
		(fp_line
			(start -0.7874 0.4064)
			(end -0.7874 -0.4064)
			(stroke
				(width 0.1524)
				(type default)
			)
			(layer "F.SilkS")
		)
		(fp_line
			(start 0.7874 0.4064)
			(end -0.7874 0.4064)
			(stroke
				(width 0.1524)
				(type default)
			)
			(layer "F.SilkS")
		)
		(fp_line
			(start -0.7874 -0.4064)
			(end 0.7874 -0.4064)
			(stroke
				(width 0.1524)
				(type default)
			)
			(layer "F.SilkS")
		)
		(fp_line
			(start 0.7874 -0.4064)
			(end 0.7874 0.4064)
			(stroke
				(width 0.1524)
				(type default)
			)
			(layer "F.SilkS")
		)
		(fp_line
			(start -0.67945 0.3048)
			(end -0.67945 -0.305054)
			(stroke
				(width 0.1)
				(type default)
			)
			(layer "F.Fab")
		)
		(fp_line
			(start -0.12065 0.3048)
			(end -0.67945 0.3048)
			(stroke
				(width 0.1)
				(type default)
			)
			(layer "F.Fab")
		)
		(fp_line
			(start 0.120396 0.3048)
			(end 0.120396 0.2794)
			(stroke
				(width 0.1)
				(type default)
			)
			(layer "F.Fab")
		)
		(fp_line
			(start 0.67945 0.3048)
			(end 0.120396 0.3048)
			(stroke
				(width 0.1)
				(type default)
			)
			(layer "F.Fab")
		)
		(fp_line
			(start -0.12065 0.2794)
			(end -0.12065 0.3048)
			(stroke
				(width 0.1)
				(type default)
			)
			(layer "F.Fab")
		)
		(fp_line
			(start 0.120396 0.2794)
			(end -0.12065 0.2794)
			(stroke
				(width 0.1)
				(type default)
			)
			(layer "F.Fab")
		)
		(fp_line
			(start -0.12065 -0.2794)
			(end 0.12065 -0.2794)
			(stroke
				(width 0.1)
				(type default)
			)
			(layer "F.Fab")
		)
		(fp_line
			(start 0.12065 -0.2794)
			(end 0.12065 -0.3048)
			(stroke
				(width 0.1)
				(type default)
			)
			(layer "F.Fab")
		)
		(fp_line
			(start 0.12065 -0.3048)
			(end 0.67945 -0.3048)
			(stroke
				(width 0.1)
				(type default)
			)
			(layer "F.Fab")
		)
		(fp_line
			(start 0.67945 -0.3048)
			(end 0.67945 0.3048)
			(stroke
				(width 0.1)
				(type default)
			)
			(layer "F.Fab")
		)
		(fp_line
			(start -0.67945 -0.305054)
			(end -0.12065 -0.305054)
			(stroke
				(width 0.1)
				(type default)
			)
			(layer "F.Fab")
		)
		(fp_line
			(start -0.12065 -0.305054)
			(end -0.12065 -0.2794)
			(stroke
				(width 0.1)
				(type default)
			)
			(layer "F.Fab")
		)
		(pad "1" smd circle
			(at -0.40005 0 270)
			(size 0 0)
			(layers "F.Cu" "F.Mask" "F.Paste")
			(net "P12V_AUX")
		)
		(pad "2" smd circle
			(at 0.40005 0 270)
			(size 0 0)
			(layers "F.Cu" "F.Mask" "F.Paste")
			(net "VR_P5V_EN_D_R")
		)
	)
)
